(kicad_pcb
	(version 20260206)
	(generator "pcbnew")
	(generator_version "10.0")
	(general
		(thickness 1.6)
		(legacy_teardrops no)
	)
	(paper "A4")
	(title_block
		(title "v1-chassis-manager — T6M_CM_d_v01_1031_1645.brd")
		(comment 1 "Open CloudServer (Microsoft) / footprints 761-770 of 2512")
	)
	(layers
		(0 "F.Cu" signal "TOP")
		(4 "In1.Cu" signal "GND1")
		(6 "In2.Cu" signal "IN1")
		(8 "In3.Cu" signal "VCC1")
		(10 "In4.Cu" signal "VCC2")
		(12 "In5.Cu" signal "GND2")
		(14 "In6.Cu" signal "IN2")
		(16 "In7.Cu" signal "IN3")
		(18 "In8.Cu" signal "GND3")
		(2 "B.Cu" signal "BOTTOM")
		(9 "F.Adhes" user "F.Adhesive")
		(11 "B.Adhes" user "B.Adhesive")
		(13 "F.Paste" user "Package Geometry/Pastemask Top")
		(15 "B.Paste" user "Package Geometry/Pastemask Bottom")
		(5 "F.SilkS" user "Ref Des/Silkscreen Top")
		(7 "B.SilkS" user "Ref Des/Silkscreen Bottom")
		(1 "F.Mask" user "Board Geometry/Soldermask Top")
		(3 "B.Mask" user "Board Geometry/Soldermask Bottom")
		(17 "Dwgs.User" user "User.Drawings")
		(19 "Cmts.User" user "User.Comments")
		(21 "Eco1.User" user "User.Eco1")
		(23 "Eco2.User" user "User.Eco2")
		(25 "Edge.Cuts" user "Board Geometry/Outline")
		(27 "Margin" user)
		(31 "F.CrtYd" user "Package Geometry/Place Bound Top")
		(29 "B.CrtYd" user "Package Geometry/Place Bound Bottom")
		(35 "F.Fab" user "Ref Des/Assembly Top")
		(33 "B.Fab" user "Ref Des/Assembly Bottom")
	)
	(footprint ""
		(layer "F.Cu")
		(at 136.25576 -110.783624 -90)
		(property "Reference" "R23"
			(at 5.84835 -0.374142 90)
			(unlocked yes)
			(layer "F.SilkS")
			(effects
				(font
					(size 0.7874 0.5842)
					(thickness 0.1524)
				)
				(justify left)
			)
		)
		(property "Value" ""
			(at 0 0 270)
			(layer "F.Fab")
			(effects
				(font
					(size 1.27 1.27)
				)
			)
		)
		(duplicate_pad_numbers_are_jumpers no)
		(fp_line
			(start -0.7874 0.4064)
			(end -0.7874 -0.4064)
			(stroke
				(width 0.1524)
				(type default)
			)
			(layer "F.SilkS")
		)
		(fp_line
			(start 0.7874 0.4064)
			(end -0.7874 0.4064)
			(stroke
				(width 0.1524)
				(type default)
			)
			(layer "F.SilkS")
		)
		(fp_line
			(start -0.7874 -0.4064)
			(end 0.7874 -0.4064)
			(stroke
				(width 0.1524)
				(type default)
			)
			(layer "F.SilkS")
		)
		(fp_line
			(start 0.7874 -0.4064)
			(end 0.7874 0.4064)
			(stroke
				(width 0.1524)
				(type default)
			)
			(layer "F.SilkS")
		)
		(fp_poly
			(pts
				(xy -0.508 0.2794) (xy -0.508 0.2286) (xy -0.635 0.2286) (xy -0.635 -0.254) (xy -0.5334 -0.254)
				(xy -0.5334 -0.2794) (xy 0.5334 -0.2794) (xy 0.5334 -0.254) (xy 0.635 -0.254) (xy 0.635 0.254) (xy 0.5334 0.254)
				(xy 0.5334 0.2794)
			)
			(stroke
				(width 0)
				(type default)
			)
			(fill no)
			(layer "F.CrtYd")
		)
		(pad "1" smd rect
			(at 0.40005 0 270)
			(size 0.4572 0.508)
			(layers "F.Cu" "F.Mask" "F.Paste")
			(net "GND")
		)
		(pad "2" smd rect
			(at -0.40005 0 270)
			(size 0.4572 0.508)
			(layers "F.Cu" "F.Mask" "F.Paste")
			(net "CLKREQA_NODE1_N")
		)
	)
	(footprint ""
		(layer "F.Cu")
		(at 24.14524 -41.591992 180)
		(property "Reference" "D8"
			(at 0.09017 -2.29743 0)
			(unlocked yes)
			(layer "F.SilkS")
			(effects
				(font
					(size 0.7874 0.5842)
					(thickness 0.1524)
				)
			)
		)
		(property "Value" ""
			(at 0 0 180)
			(layer "F.Fab")
			(effects
				(font
					(size 1.27 1.27)
				)
			)
		)
		(duplicate_pad_numbers_are_jumpers no)
		(fp_line
			(start 1.519936 1.6002)
			(end -1.519936 1.6002)
			(stroke
				(width 0.1524)
				(type default)
			)
			(layer "F.SilkS")
		)
		(fp_line
			(start 1.519936 -1.6002)
			(end 1.519936 1.6002)
			(stroke
				(width 0.1524)
				(type default)
			)
			(layer "F.SilkS")
		)
		(fp_line
			(start -1.519936 1.6002)
			(end -1.519936 -1.5748)
			(stroke
				(width 0.1524)
				(type default)
			)
			(layer "F.SilkS")
		)
		(fp_line
			(start -1.519936 -1.6002)
			(end 1.519936 -1.6002)
			(stroke
				(width 0.1524)
				(type default)
			)
			(layer "F.SilkS")
		)
		(fp_poly
			(pts
				(xy -1.519936 0.700024) (xy -1.3716 0.700024) (xy -1.3716 1.4732) (xy -0.5334 1.4732) (xy -0.5334 0.700024)
				(xy 0.5334 0.700024) (xy 0.5334 1.4732) (xy 1.3716 1.4732) (xy 1.3716 0.700024) (xy 1.519936 0.700024)
				(xy 1.519936 -0.700024) (xy 0.4064 -0.700024) (xy 0.4064 -1.4732) (xy -0.4064 -1.4732) (xy -0.4064 -0.700024)
				(xy -1.519936 -0.700024)
			)
			(stroke
				(width 0)
				(type default)
			)
			(fill no)
			(layer "F.CrtYd")
		)
		(fp_line
			(start 1.519936 0.700024)
			(end -1.519936 0.700024)
			(stroke
				(width 0.1)
				(type default)
			)
			(layer "F.Fab")
		)
		(fp_line
			(start 1.519936 -0.700024)
			(end 1.519936 0.700024)
			(stroke
				(width 0.1)
				(type default)
			)
			(layer "F.Fab")
		)
		(fp_line
			(start -1.519936 0.700024)
			(end -1.519936 -0.700024)
			(stroke
				(width 0.1)
				(type default)
			)
			(layer "F.Fab")
		)
		(fp_line
			(start -1.519936 -0.700024)
			(end 1.519936 -0.700024)
			(stroke
				(width 0.1)
				(type default)
			)
			(layer "F.Fab")
		)
		(fp_text user "3"
			(at -0.915416 -2.25552 0)
			(unlocked yes)
			(layer "F.SilkS")
			(effects
				(font
					(size 0.635 0.4064)
					(thickness 0.1524)
				)
			)
		)
		(fp_text user "1"
			(at -1.72085 1.051814 0)
			(unlocked yes)
			(layer "F.SilkS")
			(effects
				(font
					(size 0.635 0.4064)
					(thickness 0.1524)
				)
			)
		)
		(fp_text user "2"
			(at -3.20167 1.05791 0)
			(unlocked yes)
			(layer "F.SilkS")
			(effects
				(font
					(size 0.635 0.4064)
					(thickness 0.1524)
				)
			)
		)
		(pad "1" smd rect
			(at -0.94996 0.999998 180)
			(size 0.8128 0.9144)
			(layers "F.Cu" "F.Mask" "F.Paste")
			(net "SMB_BMC_NODE1_DDC_DAT")
		)
		(pad "2" smd rect
			(at 0.94996 0.999998 180)
			(size 0.8128 0.9144)
			(layers "F.Cu" "F.Mask" "F.Paste")
			(net "Net_1680")
		)
		(pad "3" smd rect
			(at 0 -0.999998 180)
			(size 0.8128 0.9144)
			(layers "F.Cu" "F.Mask" "F.Paste")
			(net "I2C_VIDREAR_5V_SDA")
		)
	)
	(footprint ""
		(layer "F.Cu")
		(at 143.36776 -188.126624 -90)
		(property "Reference" "R999"
			(at -5.519674 0.767588 90)
			(unlocked yes)
			(layer "F.SilkS")
			(effects
				(font
					(size 0.7874 0.5842)
					(thickness 0.1524)
				)
				(justify left)
			)
		)
		(property "Value" ""
			(at 0 0 270)
			(layer "F.Fab")
			(effects
				(font
					(size 1.27 1.27)
				)
			)
		)
		(duplicate_pad_numbers_are_jumpers no)
		(fp_line
			(start -0.7874 0.4064)
			(end -0.7874 -0.4064)
			(stroke
				(width 0.1524)
				(type default)
			)
			(layer "F.SilkS")
		)
		(fp_line
			(start 0.7874 0.4064)
			(end -0.7874 0.4064)
			(stroke
				(width 0.1524)
				(type default)
			)
			(layer "F.SilkS")
		)
		(fp_line
			(start -0.7874 -0.4064)
			(end 0.7874 -0.4064)
			(stroke
				(width 0.1524)
				(type default)
			)
			(layer "F.SilkS")
		)
		(fp_line
			(start 0.7874 -0.4064)
			(end 0.7874 0.4064)
			(stroke
				(width 0.1524)
				(type default)
			)
			(layer "F.SilkS")
		)
		(fp_poly
			(pts
				(xy -0.508 0.2794) (xy -0.508 0.2286) (xy -0.635 0.2286) (xy -0.635 -0.254) (xy -0.5334 -0.254)
				(xy -0.5334 -0.2794) (xy 0.5334 -0.2794) (xy 0.5334 -0.254) (xy 0.635 -0.254) (xy 0.635 0.254) (xy 0.5334 0.254)
				(xy 0.5334 0.2794)
			)
			(stroke
				(width 0)
				(type default)
			)
			(fill no)
			(layer "F.CrtYd")
		)
		(pad "1" smd rect
			(at 0.40005 0 270)
			(size 0.4572 0.508)
			(layers "F.Cu" "F.Mask" "F.Paste")
			(net "UART_T12_NODE4_RXD")
		)
		(pad "2" smd rect
			(at -0.40005 0 270)
			(size 0.4572 0.508)
			(layers "F.Cu" "F.Mask" "F.Paste")
			(net "UART_T12_NODE4_RXD_R")
		)
	)
	(footprint ""
		(layer "F.Cu")
		(at 116.630196 -28.97886 -90)
		(property "Reference" "C854"
			(at -2.034286 -0.75565 90)
			(unlocked yes)
			(layer "F.SilkS")
			(effects
				(font
					(size 0.7874 0.5842)
					(thickness 0.1524)
				)
				(justify left)
			)
		)
		(property "Value" ""
			(at 0 0 270)
			(layer "F.Fab")
			(effects
				(font
					(size 1.27 1.27)
				)
			)
		)
		(duplicate_pad_numbers_are_jumpers no)
		(fp_line
			(start -1.905 0.8636)
			(end -1.905 -0.8636)
			(stroke
				(width 0.1524)
				(type default)
			)
			(layer "F.SilkS")
		)
		(fp_line
			(start 1.905 0.8636)
			(end -1.905 0.8636)
			(stroke
				(width 0.1524)
				(type default)
			)
			(layer "F.SilkS")
		)
		(fp_line
			(start 0 0.8382)
			(end 0 -0.8382)
			(stroke
				(width 0.1524)
				(type default)
			)
			(layer "F.SilkS")
		)
		(fp_line
			(start -1.905 -0.8636)
			(end 1.905 -0.8636)
			(stroke
				(width 0.1524)
				(type default)
			)
			(layer "F.SilkS")
		)
		(fp_line
			(start 1.905 -0.8636)
			(end 1.905 0.8636)
			(stroke
				(width 0.1524)
				(type default)
			)
			(layer "F.SilkS")
		)
		(fp_rect
			(start -1.524 0.7366)
			(end 1.524 -0.7366)
			(stroke
				(width 0)
				(type default)
			)
			(fill no)
			(layer "F.CrtYd")
		)
		(pad "1" smd rect
			(at 0.94996 0 270)
			(size 1.1176 1.3716)
			(layers "F.Cu" "F.Mask" "F.Paste")
			(net "PV_VDDR_NODE1")
		)
		(pad "2" smd rect
			(at -0.94996 0 270)
			(size 1.1176 1.3716)
			(layers "F.Cu" "F.Mask" "F.Paste")
			(net "GND")
		)
	)
	(footprint ""
		(layer "F.Cu")
		(at 52.223162 -148.562822 180)
		(property "Reference" "R543"
			(at 2.1336 -5.273548 0)
			(unlocked yes)
			(layer "F.SilkS")
			(effects
				(font
					(size 0.7874 0.5842)
					(thickness 0.1524)
				)
				(justify left)
			)
		)
		(property "Value" ""
			(at 0 0 180)
			(layer "F.Fab")
			(effects
				(font
					(size 1.27 1.27)
				)
			)
		)
		(duplicate_pad_numbers_are_jumpers no)
		(fp_line
			(start 0.7874 0.4064)
			(end -0.7874 0.4064)
			(stroke
				(width 0.1524)
				(type default)
			)
			(layer "F.SilkS")
		)
		(fp_line
			(start 0.7874 -0.4064)
			(end 0.7874 0.4064)
			(stroke
				(width 0.1524)
				(type default)
			)
			(layer "F.SilkS")
		)
		(fp_line
			(start -0.7874 0.4064)
			(end -0.7874 -0.4064)
			(stroke
				(width 0.1524)
				(type default)
			)
			(layer "F.SilkS")
		)
		(fp_line
			(start -0.7874 -0.4064)
			(end 0.7874 -0.4064)
			(stroke
				(width 0.1524)
				(type default)
			)
			(layer "F.SilkS")
		)
		(fp_poly
			(pts
				(xy -0.508 0.2794) (xy -0.508 0.2286) (xy -0.635 0.2286) (xy -0.635 -0.254) (xy -0.5334 -0.254)
				(xy -0.5334 -0.2794) (xy 0.5334 -0.2794) (xy 0.5334 -0.254) (xy 0.635 -0.254) (xy 0.635 0.254) (xy 0.5334 0.254)
				(xy 0.5334 0.2794)
			)
			(stroke
				(width 0)
				(type default)
			)
			(fill no)
			(layer "F.CrtYd")
		)
		(pad "1" smd rect
			(at 0.40005 0 180)
			(size 0.4572 0.508)
			(layers "F.Cu" "F.Mask" "F.Paste")
			(net "SPI_LAN1_NVM_CS_N")
		)
		(pad "2" smd rect
			(at -0.40005 0 180)
			(size 0.4572 0.508)
			(layers "F.Cu" "F.Mask" "F.Paste")
			(net "LAN1_NVM_CS_N_R")
		)
	)
	(footprint ""
		(layer "F.Cu")
		(at 42.11828 -110.955836)
		(property "Reference" "PR8"
			(at -1.338326 -4.656328 0)
			(unlocked yes)
			(layer "F.SilkS")
			(effects
				(font
					(size 0.7874 0.5842)
					(thickness 0.1524)
				)
				(justify left)
			)
		)
		(property "Value" ""
			(at 0 0 0)
			(layer "F.Fab")
			(effects
				(font
					(size 1.27 1.27)
				)
			)
		)
		(duplicate_pad_numbers_are_jumpers no)
		(fp_line
			(start -0.7874 -0.4064)
			(end 0.7874 -0.4064)
			(stroke
				(width 0.1524)
				(type default)
			)
			(layer "F.SilkS")
		)
		(fp_line
			(start -0.7874 0.4064)
			(end -0.7874 -0.4064)
			(stroke
				(width 0.1524)
				(type default)
			)
			(layer "F.SilkS")
		)
		(fp_line
			(start 0.7874 -0.4064)
			(end 0.7874 0.4064)
			(stroke
				(width 0.1524)
				(type default)
			)
			(layer "F.SilkS")
		)
		(fp_line
			(start 0.7874 0.4064)
			(end -0.7874 0.4064)
			(stroke
				(width 0.1524)
				(type default)
			)
			(layer "F.SilkS")
		)
		(fp_poly
			(pts
				(xy -0.508 0.2794) (xy -0.508 0.2286) (xy -0.635 0.2286) (xy -0.635 -0.254) (xy -0.5334 -0.254)
				(xy -0.5334 -0.2794) (xy 0.5334 -0.2794) (xy 0.5334 -0.254) (xy 0.635 -0.254) (xy 0.635 0.254) (xy 0.5334 0.254)
				(xy 0.5334 0.2794)
			)
			(stroke
				(width 0)
				(type default)
			)
			(fill no)
			(layer "F.CrtYd")
		)
		(pad "1" smd rect
			(at 0.40005 0)
			(size 0.4572 0.508)
			(layers "F.Cu" "F.Mask" "F.Paste")
			(net "P3V3_STB_NODE1_FB")
		)
		(pad "2" smd rect
			(at -0.40005 0)
			(size 0.4572 0.508)
			(layers "F.Cu" "F.Mask" "F.Paste")
			(net "GND")
		)
	)
	(footprint ""
		(layer "F.Cu")
		(at 19.375628 -148.263102)
		(property "Reference" "C416"
			(at -3.673348 0.213614 0)
			(unlocked yes)
			(layer "F.SilkS")
			(effects
				(font
					(size 0.7874 0.5842)
					(thickness 0.1524)
				)
			)
		)
		(property "Value" ""
			(at 0 0 0)
			(layer "F.Fab")
			(effects
				(font
					(size 1.27 1.27)
				)
			)
		)
		(duplicate_pad_numbers_are_jumpers no)
		(fp_line
			(start -1.2954 -0.5842)
			(end 1.2954 -0.5842)
			(stroke
				(width 0.1524)
				(type default)
			)
			(layer "F.SilkS")
		)
		(fp_line
			(start -1.2954 0.5842)
			(end -1.2954 -0.5842)
			(stroke
				(width 0.1524)
				(type default)
			)
			(layer "F.SilkS")
		)
		(fp_line
			(start 0 -0.5842)
			(end 0 0.5842)
			(stroke
				(width 0.1524)
				(type default)
			)
			(layer "F.SilkS")
		)
		(fp_line
			(start 1.2954 -0.5842)
			(end 1.2954 0.5842)
			(stroke
				(width 0.1524)
				(type default)
			)
			(layer "F.SilkS")
		)
		(fp_line
			(start 1.2954 0.5842)
			(end -1.2954 0.5842)
			(stroke
				(width 0.1524)
				(type default)
			)
			(layer "F.SilkS")
		)
		(fp_poly
			(pts
				(xy 0.8636 -0.4572) (xy 0.8636 -0.3556) (xy 1.143 -0.3556) (xy 1.143 0.3556) (xy 0.8636 0.3556)
				(xy 0.8636 0.4572) (xy -0.8636 0.4572) (xy -0.8636 0.3556) (xy -1.143 0.3556) (xy -1.143 -0.3556)
				(xy -0.8636 -0.3556) (xy -0.8636 -0.4572)
			)
			(stroke
				(width 0)
				(type default)
			)
			(fill no)
			(layer "F.CrtYd")
		)
		(fp_line
			(start -0.884936 -0.504952)
			(end 0.884936 -0.504952)
			(stroke
				(width 0.1)
				(type default)
			)
			(layer "F.Fab")
		)
		(fp_line
			(start -0.884936 0.504952)
			(end -0.884936 -0.504952)
			(stroke
				(width 0.1)
				(type default)
			)
			(layer "F.Fab")
		)
		(fp_line
			(start 0.884936 -0.504952)
			(end 0.884936 0.504952)
			(stroke
				(width 0.1)
				(type default)
			)
			(layer "F.Fab")
		)
		(fp_line
			(start 0.884936 0.504952)
			(end -0.884936 0.504952)
			(stroke
				(width 0.1)
				(type default)
			)
			(layer "F.Fab")
		)
		(pad "1" smd rect
			(at 0.7366 0 90)
			(size 0.7112 0.8128)
			(layers "F.Cu" "F.Mask" "F.Paste")
			(net "P3V3_NODE1")
		)
		(pad "2" smd rect
			(at -0.7366 0 90)
			(size 0.7112 0.8128)
			(layers "F.Cu" "F.Mask" "F.Paste")
			(net "GND")
		)
	)
	(footprint ""
		(layer "F.Cu")
		(at 54.033166 -96.709992 90)
		(property "Reference" "R83"
			(at -54.98719 28.429712 90)
			(unlocked yes)
			(layer "F.SilkS")
			(effects
				(font
					(size 0.7874 0.5842)
					(thickness 0.1524)
				)
				(justify left)
			)
		)
		(property "Value" ""
			(at 0 0 90)
			(layer "F.Fab")
			(effects
				(font
					(size 1.27 1.27)
				)
			)
		)
		(duplicate_pad_numbers_are_jumpers no)
		(fp_line
			(start 0.7874 -0.4064)
			(end 0.7874 0.4064)
			(stroke
				(width 0.1524)
				(type default)
			)
			(layer "F.SilkS")
		)
		(fp_line
			(start -0.7874 -0.4064)
			(end 0.7874 -0.4064)
			(stroke
				(width 0.1524)
				(type default)
			)
			(layer "F.SilkS")
		)
		(fp_line
			(start 0.7874 0.4064)
			(end -0.7874 0.4064)
			(stroke
				(width 0.1524)
				(type default)
			)
			(layer "F.SilkS")
		)
		(fp_line
			(start -0.7874 0.4064)
			(end -0.7874 -0.4064)
			(stroke
				(width 0.1524)
				(type default)
			)
			(layer "F.SilkS")
		)
		(fp_poly
			(pts
				(xy -0.508 0.2794) (xy -0.508 0.2286) (xy -0.635 0.2286) (xy -0.635 -0.254) (xy -0.5334 -0.254)
				(xy -0.5334 -0.2794) (xy 0.5334 -0.2794) (xy 0.5334 -0.254) (xy 0.635 -0.254) (xy 0.635 0.254) (xy 0.5334 0.254)
				(xy 0.5334 0.2794)
			)
			(stroke
				(width 0)
				(type default)
			)
			(fill no)
			(layer "F.CrtYd")
		)
		(pad "1" smd rect
			(at 0.40005 0 90)
			(size 0.4572 0.508)
			(layers "F.Cu" "F.Mask" "F.Paste")
			(net "GND")
		)
		(pad "2" smd rect
			(at -0.40005 0 90)
			(size 0.4572 0.508)
			(layers "F.Cu" "F.Mask" "F.Paste")
			(net "PD_CPU_NODE1_DFX_GPIO_GRP0_2")
		)
	)
	(footprint ""
		(layer "F.Cu")
		(at 142.954248 -159.787336 -90)
		(property "Reference" "R1057"
			(at 110.310168 66.533522 90)
			(unlocked yes)
			(layer "F.SilkS")
			(effects
				(font
					(size 0.7874 0.5842)
					(thickness 0.1524)
				)
				(justify left)
			)
		)
		(property "Value" ""
			(at 0 0 270)
			(layer "F.Fab")
			(effects
				(font
					(size 1.27 1.27)
				)
			)
		)
		(duplicate_pad_numbers_are_jumpers no)
		(fp_line
			(start -0.7874 0.4064)
			(end -0.7874 -0.4064)
			(stroke
				(width 0.1524)
				(type default)
			)
			(layer "F.SilkS")
		)
		(fp_line
			(start 0.7874 0.4064)
			(end -0.7874 0.4064)
			(stroke
				(width 0.1524)
				(type default)
			)
			(layer "F.SilkS")
		)
		(fp_line
			(start -0.7874 -0.4064)
			(end 0.7874 -0.4064)
			(stroke
				(width 0.1524)
				(type default)
			)
			(layer "F.SilkS")
		)
		(fp_line
			(start 0.7874 -0.4064)
			(end 0.7874 0.4064)
			(stroke
				(width 0.1524)
				(type default)
			)
			(layer "F.SilkS")
		)
		(fp_poly
			(pts
				(xy -0.508 0.2794) (xy -0.508 0.2286) (xy -0.635 0.2286) (xy -0.635 -0.254) (xy -0.5334 -0.254)
				(xy -0.5334 -0.2794) (xy 0.5334 -0.2794) (xy 0.5334 -0.254) (xy 0.635 -0.254) (xy 0.635 0.254) (xy 0.5334 0.254)
				(xy 0.5334 0.2794)
			)
			(stroke
				(width 0)
				(type default)
			)
			(fill no)
			(layer "F.CrtYd")
		)
		(pad "1" smd rect
			(at 0.40005 0 270)
			(size 0.4572 0.508)
			(layers "F.Cu" "F.Mask" "F.Paste")
			(net "P3V3_NODE1")
		)
		(pad "2" smd rect
			(at -0.40005 0 270)
			(size 0.4572 0.508)
			(layers "F.Cu" "F.Mask" "F.Paste")
			(net "N31521709")
		)
	)
	(footprint ""
		(layer "F.Cu")
		(at 65.383664 -176.26203 180)
		(property "Reference" "R1014"
			(at 14.220952 -132.954014 0)
			(unlocked yes)
			(layer "F.SilkS")
			(effects
				(font
					(size 0.7874 0.5842)
					(thickness 0.1524)
				)
				(justify left)
			)
		)
		(property "Value" ""
			(at 0 0 180)
			(layer "F.Fab")
			(effects
				(font
					(size 1.27 1.27)
				)
			)
		)
		(duplicate_pad_numbers_are_jumpers no)
		(fp_line
			(start 0.7874 0.4064)
			(end -0.7874 0.4064)
			(stroke
				(width 0.1524)
				(type default)
			)
			(layer "F.SilkS")
		)
		(fp_line
			(start 0.7874 -0.4064)
			(end 0.7874 0.4064)
			(stroke
				(width 0.1524)
				(type default)
			)
			(layer "F.SilkS")
		)
		(fp_line
			(start -0.7874 0.4064)
			(end -0.7874 -0.4064)
			(stroke
				(width 0.1524)
				(type default)
			)
			(layer "F.SilkS")
		)
		(fp_line
			(start -0.7874 -0.4064)
			(end 0.7874 -0.4064)
			(stroke
				(width 0.1524)
				(type default)
			)
			(layer "F.SilkS")
		)
		(fp_poly
			(pts
				(xy -0.508 0.2794) (xy -0.508 0.2286) (xy -0.635 0.2286) (xy -0.635 -0.254) (xy -0.5334 -0.254)
				(xy -0.5334 -0.2794) (xy 0.5334 -0.2794) (xy 0.5334 -0.254) (xy 0.635 -0.254) (xy 0.635 0.254) (xy 0.5334 0.254)
				(xy 0.5334 0.2794)
			)
			(stroke
				(width 0)
				(type default)
			)
			(fill no)
			(layer "F.CrtYd")
		)
		(pad "1" smd rect
			(at 0.40005 0 180)
			(size 0.4572 0.508)
			(layers "F.Cu" "F.Mask" "F.Paste")
			(net "GND")
		)
		(pad "2" smd rect
			(at -0.40005 0 180)
			(size 0.4572 0.508)
			(layers "F.Cu" "F.Mask" "F.Paste")
			(net "PSU_DC_OK_N")
		)
	)
)
